# T6G (Grand Teton) — schematic netlist excerpt (pin names and nets, part order shuffled) for the footprints in the layout excerpt that follows; sources: Cadence DE-HDL packaged netlist, KiCad conversion of 04192023_DAF0TMB3IC0_F0TG_MB_C_brd_V02_OCP.brd

PC6530  Q_CAP  22UF 4V 20% X6S  pkg C0805  page 361 : A = P1V8_CPU1_RT_1D ; B = GND
PC6528  Q_CAP  22UF 4V 20% X6S  pkg C0805  page 361 : A = P1V8_CPU1_RT_1D ; B = GND
R737  Q_RES  10K 5% CHIP  pkg 0402LF  page 76 : A = PVDD18_S5_P0 ; B = CPU0_ROM_TYPE_SELECT

(kicad_pcb
	(version 20260206)
	(generator "pcbnew")
	(generator_version "10.0")
	(general
		(thickness 1.6)
		(legacy_teardrops no)
	)
	(paper "A4")
	(title_block
		(title "04192023_DAF0TMB3IC0_F0TG_MB_C_brd_V02_OCP.brd")
		(comment 1 "Grand Teton / footprints 5067-5069 of 8354")
	)
	(layers
		(0 "F.Cu" signal "TOP")
		(4 "In1.Cu" signal "GND")
		(6 "In2.Cu" signal "IN1")
		(8 "In3.Cu" signal "GND1")
		(10 "In4.Cu" signal "IN2")
		(12 "In5.Cu" signal "GND2")
		(14 "In6.Cu" signal "IN3")
		(16 "In7.Cu" signal "GND3")
		(18 "In8.Cu" signal "VCC")
		(20 "In9.Cu" signal "VCC1")
		(22 "In10.Cu" signal "GND4")
		(24 "In11.Cu" signal "IN4")
		(26 "In12.Cu" signal "GND5")
		(28 "In13.Cu" signal "IN5")
		(30 "In14.Cu" signal "GND6")
		(32 "In15.Cu" signal "IN6")
		(34 "In16.Cu" signal "GND7")
		(2 "B.Cu" signal "BOTTOM")
		(9 "F.Adhes" user "F.Adhesive")
		(11 "B.Adhes" user "B.Adhesive")
		(13 "F.Paste" user "Package Geometry/Pastemask Top")
		(15 "B.Paste" user "Package Geometry/Pastemask Bottom")
		(5 "F.SilkS" user "Ref Des/Silkscreen Top")
		(7 "B.SilkS" user "Ref Des/Silkscreen Bottom")
		(1 "F.Mask" user "Board Geometry/Soldermask Top")
		(3 "B.Mask" user "Board Geometry/Soldermask Bottom")
		(17 "Dwgs.User" user "User.Drawings")
		(19 "Cmts.User" user "User.Comments")
		(21 "Eco1.User" user "User.Eco1")
		(23 "Eco2.User" user "User.Eco2")
		(25 "Edge.Cuts" user "Board Geometry/Outline")
		(27 "Margin" user)
		(31 "F.CrtYd" user "Package Geometry/Place Bound Top")
		(29 "B.CrtYd" user "Package Geometry/Place Bound Bottom")
		(35 "F.Fab" user "Ref Des/Assembly Top")
		(33 "B.Fab" user "Ref Des/Assembly Bottom")
	)
	(footprint ""
		(layer "B.Cu")
		(at 403.981158 -327.987152)
		(property "Reference" "R737"
			(at 0 0 0)
			(layer "B.SilkS")
			(hide yes)
			(effects
				(font
					(size 1.27 1.27)
				)
				(justify mirror)
			)
		)
		(property "Value" ""
			(at 0 0 0)
			(layer "B.Fab")
			(effects
				(font
					(size 1.27 1.27)
				)
				(justify mirror)
			)
		)
		(duplicate_pad_numbers_are_jumpers no)
		(fp_line
			(start -0.7874 -0.4064)
			(end -0.7874 0.4064)
			(stroke
				(width 0.1524)
				(type default)
			)
			(layer "B.SilkS")
		)
		(fp_line
			(start -0.7874 0.4064)
			(end 0.7874 0.4064)
			(stroke
				(width 0.1524)
				(type default)
			)
			(layer "B.SilkS")
		)
		(fp_line
			(start 0.7874 -0.4064)
			(end -0.7874 -0.4064)
			(stroke
				(width 0.1524)
				(type default)
			)
			(layer "B.SilkS")
		)
		(fp_line
			(start 0.7874 0.4064)
			(end 0.7874 -0.4064)
			(stroke
				(width 0.1524)
				(type default)
			)
			(layer "B.SilkS")
		)
		(fp_line
			(start -0.67945 -0.3048)
			(end -0.67945 0.3048)
			(stroke
				(width 0.1)
				(type default)
			)
			(layer "B.Fab")
		)
		(fp_line
			(start -0.67945 0.3048)
			(end -0.120396 0.3048)
			(stroke
				(width 0.1)
				(type default)
			)
			(layer "B.Fab")
		)
		(fp_line
			(start -0.12065 -0.3048)
			(end -0.67945 -0.3048)
			(stroke
				(width 0.1)
				(type default)
			)
			(layer "B.Fab")
		)
		(fp_line
			(start -0.12065 -0.2794)
			(end -0.12065 -0.3048)
			(stroke
				(width 0.1)
				(type default)
			)
			(layer "B.Fab")
		)
		(fp_line
			(start -0.120396 0.2794)
			(end 0.12065 0.2794)
			(stroke
				(width 0.1)
				(type default)
			)
			(layer "B.Fab")
		)
		(fp_line
			(start -0.120396 0.3048)
			(end -0.120396 0.2794)
			(stroke
				(width 0.1)
				(type default)
			)
			(layer "B.Fab")
		)
		(fp_line
			(start 0.12065 -0.305054)
			(end 0.12065 -0.2794)
			(stroke
				(width 0.1)
				(type default)
			)
			(layer "B.Fab")
		)
		(fp_line
			(start 0.12065 -0.2794)
			(end -0.12065 -0.2794)
			(stroke
				(width 0.1)
				(type default)
			)
			(layer "B.Fab")
		)
		(fp_line
			(start 0.12065 0.2794)
			(end 0.12065 0.3048)
			(stroke
				(width 0.1)
				(type default)
			)
			(layer "B.Fab")
		)
		(fp_line
			(start 0.12065 0.3048)
			(end 0.67945 0.3048)
			(stroke
				(width 0.1)
				(type default)
			)
			(layer "B.Fab")
		)
		(fp_line
			(start 0.67945 -0.305054)
			(end 0.12065 -0.305054)
			(stroke
				(width 0.1)
				(type default)
			)
			(layer "B.Fab")
		)
		(fp_line
			(start 0.67945 0.3048)
			(end 0.67945 -0.305054)
			(stroke
				(width 0.1)
				(type default)
			)
			(layer "B.Fab")
		)
		(pad "1" smd circle
			(at 0.40005 0 180)
			(size 0 0)
			(layers "B.Cu" "B.Mask" "B.Paste")
			(net "PVDD18_S5_P0")
		)
		(pad "2" smd circle
			(at -0.40005 0 180)
			(size 0 0)
			(layers "B.Cu" "B.Mask" "B.Paste")
			(net "CPU0_ROM_TYPE_SELECT")
		)
	)
	(footprint ""
		(layer "B.Cu")
		(at 226.777042 -315.95568 -90)
		(property "Reference" "PC6528"
			(at 0 0 90)
			(layer "B.SilkS")
			(hide yes)
			(effects
				(font
					(size 1.27 1.27)
				)
				(justify mirror)
			)
		)
		(property "Value" ""
			(at 0 0 90)
			(layer "B.Fab")
			(effects
				(font
					(size 1.27 1.27)
				)
				(justify mirror)
			)
		)
		(duplicate_pad_numbers_are_jumpers no)
		(fp_line
			(start -1.524 0.762)
			(end 1.524 0.762)
			(stroke
				(width 0.1524)
				(type default)
			)
			(layer "B.SilkS")
		)
		(fp_line
			(start 1.524 0.762)
			(end 1.524 -0.762)
			(stroke
				(width 0.1524)
				(type default)
			)
			(layer "B.SilkS")
		)
		(fp_line
			(start -1.524 -0.762)
			(end -1.524 0.762)
			(stroke
				(width 0.1524)
				(type default)
			)
			(layer "B.SilkS")
		)
		(fp_line
			(start 1.524 -0.762)
			(end -1.524 -0.762)
			(stroke
				(width 0.1524)
				(type default)
			)
			(layer "B.SilkS")
		)
		(fp_line
			(start -1.1049 0.724916)
			(end -1.1049 -0.724916)
			(stroke
				(width 0.1)
				(type default)
			)
			(layer "B.Fab")
		)
		(fp_line
			(start 1.1049 0.724916)
			(end -1.1049 0.724916)
			(stroke
				(width 0.1)
				(type default)
			)
			(layer "B.Fab")
		)
		(fp_line
			(start -1.1049 -0.724916)
			(end 1.1049 -0.724916)
			(stroke
				(width 0.1)
				(type default)
			)
			(layer "B.Fab")
		)
		(fp_line
			(start 1.1049 -0.724916)
			(end 1.1049 0.724916)
			(stroke
				(width 0.1)
				(type default)
			)
			(layer "B.Fab")
		)
		(pad "1" smd rect
			(at 0.889 0 270)
			(size 1.016 1.27)
			(layers "B.Cu" "B.Mask" "B.Paste")
			(net "P1V8_CPU1_RT_1D")
		)
		(pad "2" smd rect
			(at -0.889 0 270)
			(size 1.016 1.27)
			(layers "B.Cu" "B.Mask" "B.Paste")
			(net "GND")
		)
	)
	(footprint ""
		(layer "B.Cu")
		(at 232.669842 -315.95568 -90)
		(property "Reference" "PC6530"
			(at 0 0 90)
			(layer "B.SilkS")
			(hide yes)
			(effects
				(font
					(size 1.27 1.27)
				)
				(justify mirror)
			)
		)
		(property "Value" ""
			(at 0 0 90)
			(layer "B.Fab")
			(effects
				(font
					(size 1.27 1.27)
				)
				(justify mirror)
			)
		)
		(duplicate_pad_numbers_are_jumpers no)
		(fp_line
			(start -1.524 0.762)
			(end 1.524 0.762)
			(stroke
				(width 0.1524)
				(type default)
			)
			(layer "B.SilkS")
		)
		(fp_line
			(start 1.524 0.762)
			(end 1.524 -0.762)
			(stroke
				(width 0.1524)
				(type default)
			)
			(layer "B.SilkS")
		)
		(fp_line
			(start -1.524 -0.762)
			(end -1.524 0.762)
			(stroke
				(width 0.1524)
				(type default)
			)
			(layer "B.SilkS")
		)
		(fp_line
			(start 1.524 -0.762)
			(end -1.524 -0.762)
			(stroke
				(width 0.1524)
				(type default)
			)
			(layer "B.SilkS")
		)
		(fp_line
			(start -1.1049 0.724916)
			(end -1.1049 -0.724916)
			(stroke
				(width 0.1)
				(type default)
			)
			(layer "B.Fab")
		)
		(fp_line
			(start 1.1049 0.724916)
			(end -1.1049 0.724916)
			(stroke
				(width 0.1)
				(type default)
			)
			(layer "B.Fab")
		)
		(fp_line
			(start -1.1049 -0.724916)
			(end 1.1049 -0.724916)
			(stroke
				(width 0.1)
				(type default)
			)
			(layer "B.Fab")
		)
		(fp_line
			(start 1.1049 -0.724916)
			(end 1.1049 0.724916)
			(stroke
				(width 0.1)
				(type default)
			)
			(layer "B.Fab")
		)
		(pad "1" smd rect
			(at 0.889 0 270)
			(size 1.016 1.27)
			(layers "B.Cu" "B.Mask" "B.Paste")
			(net "P1V8_CPU1_RT_1D")
		)
		(pad "2" smd rect
			(at -0.889 0 270)
			(size 1.016 1.27)
			(layers "B.Cu" "B.Mask" "B.Paste")
			(net "GND")
		)
	)
)
